(kicad_pcb
	(version 20260206)
	(generator "pcbnew")
	(generator_version "10.0")
	(general
		(thickness 1.6)
		(legacy_teardrops no)
	)
	(paper "A4")
	(title_block
		(title "01162023_DA0F0TEBIF0_F0T_Expander_BD_F_brd_V02_OCP.brd")
		(comment 1 "Grand Teton / footprints 1963-1966 of 9728")
	)
	(layers
		(0 "F.Cu" signal "TOP")
		(4 "In1.Cu" signal "GND")
		(6 "In2.Cu" signal "VCC")
		(8 "In3.Cu" signal "VCC1")
		(10 "In4.Cu" signal "GND1")
		(12 "In5.Cu" signal "IN1")
		(14 "In6.Cu" signal "GND2")
		(16 "In7.Cu" signal "IN2")
		(18 "In8.Cu" signal "GND3")
		(20 "In9.Cu" signal "IN3")
		(22 "In10.Cu" signal "GND4")
		(24 "In11.Cu" signal "IN4")
		(26 "In12.Cu" signal "GND5")
		(28 "In13.Cu" signal "IN5")
		(30 "In14.Cu" signal "GND6")
		(32 "In15.Cu" signal "IN6")
		(34 "In16.Cu" signal "GND7")
		(2 "B.Cu" signal "BOTTOM")
		(9 "F.Adhes" user "F.Adhesive")
		(11 "B.Adhes" user "B.Adhesive")
		(13 "F.Paste" user "Package Geometry/Pastemask Top")
		(15 "B.Paste" user "Package Geometry/Pastemask Bottom")
		(5 "F.SilkS" user "Ref Des/Silkscreen Top")
		(7 "B.SilkS" user "Ref Des/Silkscreen Bottom")
		(1 "F.Mask" user "Board Geometry/Soldermask Top")
		(3 "B.Mask" user "Board Geometry/Soldermask Bottom")
		(17 "Dwgs.User" user "User.Drawings")
		(19 "Cmts.User" user "User.Comments")
		(21 "Eco1.User" user "User.Eco1")
		(23 "Eco2.User" user "User.Eco2")
		(25 "Edge.Cuts" user "Board Geometry/Outline")
		(27 "Margin" user)
		(31 "F.CrtYd" user "Package Geometry/Place Bound Top")
		(29 "B.CrtYd" user "Package Geometry/Place Bound Bottom")
		(35 "F.Fab" user "Ref Des/Assembly Top")
		(33 "B.Fab" user "Ref Des/Assembly Bottom")
	)
	(footprint ""
		(layer "F.Cu")
		(at 232.06964 -83.718908 180)
		(property "Reference" "R6287"
			(at 0 0 180)
			(layer "F.SilkS")
			(hide yes)
			(effects
				(font
					(size 1.27 1.27)
				)
			)
		)
		(property "Value" ""
			(at 0 0 180)
			(layer "F.Fab")
			(effects
				(font
					(size 1.27 1.27)
				)
			)
		)
		(duplicate_pad_numbers_are_jumpers no)
		(fp_line
			(start 0.7874 0.4064)
			(end -0.001016 0.4064)
			(stroke
				(width 0.1524)
				(type default)
			)
			(layer "F.SilkS")
		)
		(fp_line
			(start 0.7874 -0.4064)
			(end 0.7874 0.4064)
			(stroke
				(width 0.1524)
				(type default)
			)
			(layer "F.SilkS")
		)
		(fp_line
			(start -0.7874 0.4064)
			(end -0.7874 -0.4064)
			(stroke
				(width 0.1524)
				(type default)
			)
			(layer "F.SilkS")
		)
		(fp_line
			(start -0.7874 -0.4064)
			(end 0.7874 -0.4064)
			(stroke
				(width 0.1524)
				(type default)
			)
			(layer "F.SilkS")
		)
		(fp_line
			(start 0.67945 0.3048)
			(end 0.120396 0.3048)
			(stroke
				(width 0.1)
				(type default)
			)
			(layer "F.Fab")
		)
		(fp_line
			(start 0.67945 -0.3048)
			(end 0.67945 0.3048)
			(stroke
				(width 0.1)
				(type default)
			)
			(layer "F.Fab")
		)
		(fp_line
			(start 0.12065 -0.2794)
			(end 0.12065 -0.3048)
			(stroke
				(width 0.1)
				(type default)
			)
			(layer "F.Fab")
		)
		(fp_line
			(start 0.12065 -0.3048)
			(end 0.67945 -0.3048)
			(stroke
				(width 0.1)
				(type default)
			)
			(layer "F.Fab")
		)
		(fp_line
			(start 0.120396 0.3048)
			(end 0.120396 0.2794)
			(stroke
				(width 0.1)
				(type default)
			)
			(layer "F.Fab")
		)
		(fp_line
			(start 0.120396 0.2794)
			(end -0.12065 0.2794)
			(stroke
				(width 0.1)
				(type default)
			)
			(layer "F.Fab")
		)
		(fp_line
			(start -0.12065 0.3048)
			(end -0.67945 0.3048)
			(stroke
				(width 0.1)
				(type default)
			)
			(layer "F.Fab")
		)
		(fp_line
			(start -0.12065 0.2794)
			(end -0.12065 0.3048)
			(stroke
				(width 0.1)
				(type default)
			)
			(layer "F.Fab")
		)
		(fp_line
			(start -0.12065 -0.2794)
			(end 0.12065 -0.2794)
			(stroke
				(width 0.1)
				(type default)
			)
			(layer "F.Fab")
		)
		(fp_line
			(start -0.12065 -0.305054)
			(end -0.12065 -0.2794)
			(stroke
				(width 0.1)
				(type default)
			)
			(layer "F.Fab")
		)
		(fp_line
			(start -0.67945 0.3048)
			(end -0.67945 -0.305054)
			(stroke
				(width 0.1)
				(type default)
			)
			(layer "F.Fab")
		)
		(fp_line
			(start -0.67945 -0.305054)
			(end -0.12065 -0.305054)
			(stroke
				(width 0.1)
				(type default)
			)
			(layer "F.Fab")
		)
		(pad "1" smd rect
			(at -0.40005 0)
			(size 0.4572 0.508)
			(layers "F.Cu" "F.Mask" "F.Paste")
			(net "USB2_FT4232_SDB_DN")
		)
		(pad "2" smd rect
			(at 0.40005 0)
			(size 0.4572 0.508)
			(layers "F.Cu" "F.Mask" "F.Paste")
			(net "GND")
		)
	)
	(footprint ""
		(layer "F.Cu")
		(at 248.134124 -135.77697 -90)
		(property "Reference" "PC310"
			(at 0 0 270)
			(layer "F.SilkS")
			(hide yes)
			(effects
				(font
					(size 1.27 1.27)
				)
			)
		)
		(property "Value" ""
			(at 0 0 270)
			(layer "F.Fab")
			(effects
				(font
					(size 1.27 1.27)
				)
			)
		)
		(duplicate_pad_numbers_are_jumpers no)
		(fp_line
			(start -1.524 0.762)
			(end -1.524 -0.762)
			(stroke
				(width 0.1524)
				(type default)
			)
			(layer "F.SilkS")
		)
		(fp_line
			(start 1.524 0.762)
			(end -1.524 0.762)
			(stroke
				(width 0.1524)
				(type default)
			)
			(layer "F.SilkS")
		)
		(fp_line
			(start -1.524 -0.762)
			(end 1.524 -0.762)
			(stroke
				(width 0.1524)
				(type default)
			)
			(layer "F.SilkS")
		)
		(fp_line
			(start 1.524 -0.762)
			(end 1.524 0.762)
			(stroke
				(width 0.1524)
				(type default)
			)
			(layer "F.SilkS")
		)
		(fp_line
			(start -1.1049 0.724916)
			(end 1.1049 0.724916)
			(stroke
				(width 0.1)
				(type default)
			)
			(layer "F.Fab")
		)
		(fp_line
			(start 1.1049 0.724916)
			(end 1.1049 -0.724916)
			(stroke
				(width 0.1)
				(type default)
			)
			(layer "F.Fab")
		)
		(fp_line
			(start -1.1049 -0.724916)
			(end -1.1049 0.724916)
			(stroke
				(width 0.1)
				(type default)
			)
			(layer "F.Fab")
		)
		(fp_line
			(start 1.1049 -0.724916)
			(end -1.1049 -0.724916)
			(stroke
				(width 0.1)
				(type default)
			)
			(layer "F.Fab")
		)
		(pad "1" smd rect
			(at -0.889 0 90)
			(size 1.016 1.27)
			(layers "F.Cu" "F.Mask" "F.Paste")
			(net "P12V_NIC4_R")
		)
		(pad "2" smd rect
			(at 0.889 0 90)
			(size 1.016 1.27)
			(layers "F.Cu" "F.Mask" "F.Paste")
			(net "GND")
		)
	)
	(footprint ""
		(layer "F.Cu")
		(at 437.949848 -270.89989)
		(property "Reference" "H99"
			(at -4.097274 -9.201658 0)
			(unlocked yes)
			(layer "F.SilkS")
			(effects
				(font
					(size 0.7874 0.5842)
					(thickness 0.1524)
				)
				(justify left)
			)
		)
		(property "Value" ""
			(at 0 0 0)
			(layer "F.Fab")
			(effects
				(font
					(size 1.27 1.27)
				)
			)
		)
		(duplicate_pad_numbers_are_jumpers no)
		(fp_arc
			(start -5.147818 -6.123686)
			(mid 3.377705 -7.252005)
			(end 7.999984 0)
			(stroke
				(width 0.1524)
				(type default)
			)
			(layer "F.SilkS")
		)
		(fp_arc
			(start 7.999984 0)
			(mid -0.158601 7.998349)
			(end -7.993634 -0.317246)
			(stroke
				(width 0.1524)
				(type default)
			)
			(layer "F.SilkS")
		)
		(fp_arc
			(start -5.424424 -5.8801)
			(mid 3.209671 -7.327835)
			(end 7.999984 0)
			(stroke
				(width 0.1524)
				(type default)
			)
			(layer "B.SilkS")
		)
		(fp_arc
			(start 7.999984 0)
			(mid -0.421727 7.988869)
			(end -7.955534 -0.842264)
			(stroke
				(width 0.1524)
				(type default)
			)
			(layer "B.SilkS")
		)
		(fp_circle
			(center 0 0)
			(end 7.999984 0)
			(stroke
				(width 0.1)
				(type default)
			)
			(fill no)
			(layer "B.Fab")
		)
		(fp_circle
			(center 0 0)
			(end 7.999984 0)
			(stroke
				(width 0.1)
				(type default)
			)
			(fill no)
			(layer "F.Fab")
		)
		(pad "" np_thru_hole circle
			(at 0 0)
			(size 4.5212 4.5212)
			(drill 4.5212)
			(layers "*.Cu" "*.Mask")
			(clearance 0.381)
			(thermal_gap 0.381)
		)
		(pad "2" thru_hole circle
			(at 3.6322 0)
			(size 0.762 0.762)
			(drill 0.5588)
			(layers "*.Cu" "*.Mask")
			(remove_unused_layers no)
			(net "GND")
			(clearance 0.1524)
			(thermal_gap 0.1524)
		)
		(pad "3" thru_hole circle
			(at 2.568448 -2.568448)
			(size 0.762 0.762)
			(drill 0.5588)
			(layers "*.Cu" "*.Mask")
			(remove_unused_layers no)
			(net "GND")
			(clearance 0.1524)
			(thermal_gap 0.1524)
		)
		(pad "4" thru_hole circle
			(at 0 -3.6322)
			(size 0.762 0.762)
			(drill 0.5588)
			(layers "*.Cu" "*.Mask")
			(remove_unused_layers no)
			(net "GND")
			(clearance 0.1524)
			(thermal_gap 0.1524)
		)
		(pad "5" thru_hole circle
			(at -2.568448 -2.568448)
			(size 0.762 0.762)
			(drill 0.5588)
			(layers "*.Cu" "*.Mask")
			(remove_unused_layers no)
			(net "GND")
			(clearance 0.1524)
			(thermal_gap 0.1524)
		)
		(pad "6" thru_hole circle
			(at -3.6322 0)
			(size 0.762 0.762)
			(drill 0.5588)
			(layers "*.Cu" "*.Mask")
			(remove_unused_layers no)
			(net "GND")
			(clearance 0.1524)
			(thermal_gap 0.1524)
		)
		(pad "7" thru_hole circle
			(at -2.568448 2.568448)
			(size 0.762 0.762)
			(drill 0.5588)
			(layers "*.Cu" "*.Mask")
			(remove_unused_layers no)
			(net "GND")
			(clearance 0.1524)
			(thermal_gap 0.1524)
		)
		(pad "8" thru_hole circle
			(at 0 3.6322)
			(size 0.762 0.762)
			(drill 0.5588)
			(layers "*.Cu" "*.Mask")
			(remove_unused_layers no)
			(net "GND")
			(clearance 0.1524)
			(thermal_gap 0.1524)
		)
		(pad "9" thru_hole circle
			(at 2.568448 2.568448)
			(size 0.762 0.762)
			(drill 0.5588)
			(layers "*.Cu" "*.Mask")
			(remove_unused_layers no)
			(net "GND")
			(clearance 0.1524)
			(thermal_gap 0.1524)
		)
		(zone
			(layer "F.Cu")
			(hatch none 0.5)
			(connect_pads
				(clearance 0)
			)
			(min_thickness 0.25)
			(keepout
				(tracks not_allowed)
				(vias allowed)
				(pads allowed)
				(copperpour not_allowed)
				(footprints allowed)
			)
			(placement
				(enabled no)
				(sheetname "")
			)
			(fill
				(thermal_gap 0.5)
				(thermal_bridge_width 0.5)
				(island_removal_mode 0)
			)
			(polygon
				(pts
					(arc
						(start 437.949848 -262.899906)
						(mid 429.949864 -270.89989)
						(end 437.949848 -278.899874)
					)
					(arc
						(start 437.949848 -275.64969)
						(mid 433.200048 -270.89989)
						(end 437.949848 -266.15009)
					)
				)
			)
		)
		(zone
			(layer "F.Cu")
			(hatch none 0.5)
			(connect_pads
				(clearance 0)
			)
			(min_thickness 0.25)
			(keepout
				(tracks not_allowed)
				(vias allowed)
				(pads allowed)
				(copperpour not_allowed)
				(footprints allowed)
			)
			(placement
				(enabled no)
				(sheetname "")
			)
			(fill
				(thermal_gap 0.5)
				(thermal_bridge_width 0.5)
				(island_removal_mode 0)
			)
			(polygon
				(pts
					(arc
						(start 437.949848 -262.899906)
						(mid 445.949832 -270.89989)
						(end 437.949848 -278.899874)
					)
					(arc
						(start 437.949848 -275.64969)
						(mid 442.699648 -270.89989)
						(end 437.949848 -266.15009)
					)
				)
			)
		)
		(zone
			(layers "F.Cu" "B.Cu" "In1.Cu" "In2.Cu" "In3.Cu" "In4.Cu" "In5.Cu" "In6.Cu"
				"In7.Cu" "In8.Cu" "In9.Cu" "In10.Cu" "In11.Cu" "In12.Cu" "In13.Cu" "In14.Cu"
				"In15.Cu" "In16.Cu"
			)
			(hatch none 0.5)
			(connect_pads
				(clearance 0)
			)
			(min_thickness 0.25)
			(keepout
				(tracks not_allowed)
				(vias allowed)
				(pads allowed)
				(copperpour not_allowed)
				(footprints allowed)
			)
			(placement
				(enabled no)
				(sheetname "")
			)
			(fill
				(thermal_gap 0.5)
				(thermal_bridge_width 0.5)
				(island_removal_mode 0)
			)
			(polygon
				(pts
					(arc
						(start 440.715908 -270.89989)
						(mid 435.183788 -270.89989)
						(end 440.715908 -270.89989)
					)
				)
			)
		)
		(zone
			(layer "B.Cu")
			(hatch none 0.5)
			(connect_pads
				(clearance 0)
			)
			(min_thickness 0.25)
			(keepout
				(tracks not_allowed)
				(vias allowed)
				(pads allowed)
				(copperpour not_allowed)
				(footprints allowed)
			)
			(placement
				(enabled no)
				(sheetname "")
			)
			(fill
				(thermal_gap 0.5)
				(thermal_bridge_width 0.5)
				(island_removal_mode 0)
			)
			(polygon
				(pts
					(arc
						(start 437.949848 -265.89609)
						(mid 432.946048 -270.89989)
						(end 437.949848 -275.90369)
					)
					(arc
						(start 437.949848 -275.42109)
						(mid 433.428648 -270.89989)
						(end 437.949848 -266.37869)
					)
				)
			)
		)
		(zone
			(layer "B.Cu")
			(hatch none 0.5)
			(connect_pads
				(clearance 0)
			)
			(min_thickness 0.25)
			(keepout
				(tracks not_allowed)
				(vias allowed)
				(pads allowed)
				(copperpour not_allowed)
				(footprints allowed)
			)
			(placement
				(enabled no)
				(sheetname "")
			)
			(fill
				(thermal_gap 0.5)
				(thermal_bridge_width 0.5)
				(island_removal_mode 0)
			)
			(polygon
				(pts
					(arc
						(start 437.949848 -265.89609)
						(mid 442.953648 -270.89989)
						(end 437.949848 -275.90369)
					)
					(arc
						(start 437.949848 -275.42109)
						(mid 442.471048 -270.89989)
						(end 437.949848 -266.37869)
					)
				)
			)
		)
	)
	(footprint ""
		(layer "F.Cu")
		(at 214.040212 -226.711256 180)
		(property "Reference" "R1484"
			(at 0 0 180)
			(layer "F.SilkS")
			(hide yes)
			(effects
				(font
					(size 1.27 1.27)
				)
			)
		)
		(property "Value" ""
			(at 0 0 180)
			(layer "F.Fab")
			(effects
				(font
					(size 1.27 1.27)
				)
			)
		)
		(duplicate_pad_numbers_are_jumpers no)
		(fp_line
			(start 0.7874 0.4064)
			(end -0.7874 0.4064)
			(stroke
				(width 0.1524)
				(type default)
			)
			(layer "F.SilkS")
		)
		(fp_line
			(start 0.7874 -0.4064)
			(end 0.7874 0.4064)
			(stroke
				(width 0.1524)
				(type default)
			)
			(layer "F.SilkS")
		)
		(fp_line
			(start -0.7874 0.4064)
			(end -0.7874 -0.4064)
			(stroke
				(width 0.1524)
				(type default)
			)
			(layer "F.SilkS")
		)
		(fp_line
			(start -0.7874 -0.4064)
			(end 0.7874 -0.4064)
			(stroke
				(width 0.1524)
				(type default)
			)
			(layer "F.SilkS")
		)
		(fp_line
			(start 0.67945 0.3048)
			(end 0.120396 0.3048)
			(stroke
				(width 0.1)
				(type default)
			)
			(layer "F.Fab")
		)
		(fp_line
			(start 0.67945 -0.3048)
			(end 0.67945 0.3048)
			(stroke
				(width 0.1)
				(type default)
			)
			(layer "F.Fab")
		)
		(fp_line
			(start 0.12065 -0.2794)
			(end 0.12065 -0.3048)
			(stroke
				(width 0.1)
				(type default)
			)
			(layer "F.Fab")
		)
		(fp_line
			(start 0.12065 -0.3048)
			(end 0.67945 -0.3048)
			(stroke
				(width 0.1)
				(type default)
			)
			(layer "F.Fab")
		)
		(fp_line
			(start 0.120396 0.3048)
			(end 0.120396 0.2794)
			(stroke
				(width 0.1)
				(type default)
			)
			(layer "F.Fab")
		)
		(fp_line
			(start 0.120396 0.2794)
			(end -0.12065 0.2794)
			(stroke
				(width 0.1)
				(type default)
			)
			(layer "F.Fab")
		)
		(fp_line
			(start -0.12065 0.3048)
			(end -0.67945 0.3048)
			(stroke
				(width 0.1)
				(type default)
			)
			(layer "F.Fab")
		)
		(fp_line
			(start -0.12065 0.2794)
			(end -0.12065 0.3048)
			(stroke
				(width 0.1)
				(type default)
			)
			(layer "F.Fab")
		)
		(fp_line
			(start -0.12065 -0.2794)
			(end 0.12065 -0.2794)
			(stroke
				(width 0.1)
				(type default)
			)
			(layer "F.Fab")
		)
		(fp_line
			(start -0.12065 -0.305054)
			(end -0.12065 -0.2794)
			(stroke
				(width 0.1)
				(type default)
			)
			(layer "F.Fab")
		)
		(fp_line
			(start -0.67945 0.3048)
			(end -0.67945 -0.305054)
			(stroke
				(width 0.1)
				(type default)
			)
			(layer "F.Fab")
		)
		(fp_line
			(start -0.67945 -0.305054)
			(end -0.12065 -0.305054)
			(stroke
				(width 0.1)
				(type default)
			)
			(layer "F.Fab")
		)
		(pad "1" smd circle
			(at -0.40005 0 180)
			(size 0 0)
			(layers "F.Cu" "F.Mask" "F.Paste")
			(net "SMB_NIC2_SDA")
		)
		(pad "2" smd circle
			(at 0.40005 0 180)
			(size 0 0)
			(layers "F.Cu" "F.Mask" "F.Paste")
			(net "SMB_NIC2_R_SDA")
		)
	)
)
